(kicad_pcb
	(version 20260206)
	(generator "pcbnew")
	(generator_version "10.0")
	(general
		(thickness 1.6)
		(legacy_teardrops no)
	)
	(paper "A4")
	(title_block
		(title "Wiwynn_Tioga_Pass_MB.brd")
		(comment 1 "Tioga Pass / footprints 4562-4564 of 4770")
	)
	(layers
		(0 "F.Cu" signal "TOP")
		(4 "In1.Cu" signal "L2GND")
		(6 "In2.Cu" signal "L3")
		(8 "In3.Cu" signal "L4GND")
		(10 "In4.Cu" signal "L5")
		(12 "In5.Cu" signal "L6GND")
		(14 "In6.Cu" signal "L7VCC")
		(16 "In7.Cu" signal "L8VCC")
		(18 "In8.Cu" signal "L9GND")
		(20 "In9.Cu" signal "L10")
		(22 "In10.Cu" signal "L11GND")
		(24 "In11.Cu" signal "L12")
		(26 "In12.Cu" signal "L13GND")
		(2 "B.Cu" signal "BOTTOM")
		(9 "F.Adhes" user "F.Adhesive")
		(11 "B.Adhes" user "B.Adhesive")
		(13 "F.Paste" user "Package Geometry/Pastemask Top")
		(15 "B.Paste" user "Package Geometry/Pastemask Bottom")
		(5 "F.SilkS" user "Ref Des/Silkscreen Top")
		(7 "B.SilkS" user "Ref Des/Silkscreen Bottom")
		(1 "F.Mask" user "Board Geometry/Soldermask Top")
		(3 "B.Mask" user "Board Geometry/Soldermask Bottom")
		(17 "Dwgs.User" user "User.Drawings")
		(19 "Cmts.User" user "User.Comments")
		(21 "Eco1.User" user "User.Eco1")
		(23 "Eco2.User" user "User.Eco2")
		(25 "Edge.Cuts" user "Board Geometry/Outline")
		(27 "Margin" user)
		(31 "F.CrtYd" user "Package Geometry/Place Bound Top")
		(29 "B.CrtYd" user "Package Geometry/Place Bound Bottom")
		(35 "F.Fab" user "Ref Des/Assembly Top")
		(33 "B.Fab" user "Ref Des/Assembly Bottom")
	)
	(footprint ""
		(layer "B.Cu")
		(at 437.930036 -137.044938)
		(property "Reference" "J2W1"
			(at 0 0 0)
			(layer "B.SilkS")
			(hide yes)
			(effects
				(font
					(size 1.27 1.27)
				)
				(justify mirror)
			)
		)
		(property "Value" "*"
			(at 2.3622 -8.3185 0)
			(unlocked yes)
			(layer "B.Fab")
			(hide yes)
			(effects
				(font
					(size 1.27 1.016)
					(thickness 0.1524)
				)
				(justify mirror)
			)
		)
		(property "Device Type" "SKT-SATA7P-6P-165-GP-U1_SOCKETA"
			(at 2.3622 -9.8425 0)
			(unlocked yes)
			(layer "B.Fab")
			(hide yes)
			(effects
				(font
					(size 1.27 1.016)
					(thickness 0.1524)
				)
				(justify mirror)
			)
		)
		(duplicate_pad_numbers_are_jumpers no)
		(fp_line
			(start -17.8054 -3.3909)
			(end -17.8054 2.9337)
			(stroke
				(width 0.1524)
				(type default)
			)
			(layer "B.SilkS")
		)
		(fp_line
			(start -17.8054 2.9337)
			(end 17.8054 2.9337)
			(stroke
				(width 0.1524)
				(type default)
			)
			(layer "B.SilkS")
		)
		(fp_line
			(start 3.68808 0.649224)
			(end 3.68808 0.750824)
			(stroke
				(width 0.3048)
				(type default)
			)
			(layer "B.SilkS")
		)
		(fp_line
			(start 10.21207 0.750824)
			(end 10.21207 0.649224)
			(stroke
				(width 0.3048)
				(type default)
			)
			(layer "B.SilkS")
		)
		(fp_line
			(start 17.8054 -3.3909)
			(end -17.8054 -3.3909)
			(stroke
				(width 0.1524)
				(type default)
			)
			(layer "B.SilkS")
		)
		(fp_line
			(start 17.8054 2.9337)
			(end 17.8054 -3.3909)
			(stroke
				(width 0.1524)
				(type default)
			)
			(layer "B.SilkS")
		)
		(fp_arc
			(start -8.744966 0.114808)
			(mid -8.109966 -0.163517)
			(end -7.474966 0.114808)
			(stroke
				(width 0.3048)
				(type default)
			)
			(layer "B.SilkS")
		)
		(fp_arc
			(start -8.744966 1.28524)
			(mid -10.243445 0.700048)
			(end -8.744966 0.114808)
			(stroke
				(width 0.3048)
				(type default)
			)
			(layer "B.SilkS")
		)
		(fp_arc
			(start -7.474966 0.114808)
			(mid -6.839966 -0.163517)
			(end -6.204966 0.114808)
			(stroke
				(width 0.3048)
				(type default)
			)
			(layer "B.SilkS")
		)
		(fp_arc
			(start -7.474966 1.28524)
			(mid -8.109966 1.563565)
			(end -8.744966 1.28524)
			(stroke
				(width 0.3048)
				(type default)
			)
			(layer "B.SilkS")
		)
		(fp_arc
			(start -6.204966 0.114808)
			(mid -5.569966 -0.163517)
			(end -4.934966 0.114808)
			(stroke
				(width 0.3048)
				(type default)
			)
			(layer "B.SilkS")
		)
		(fp_arc
			(start -6.204966 1.28524)
			(mid -6.839966 1.563565)
			(end -7.474966 1.28524)
			(stroke
				(width 0.3048)
				(type default)
			)
			(layer "B.SilkS")
		)
		(fp_arc
			(start -4.934966 0.114808)
			(mid -4.299966 -0.163517)
			(end -3.664966 0.114808)
			(stroke
				(width 0.3048)
				(type default)
			)
			(layer "B.SilkS")
		)
		(fp_arc
			(start -4.934966 1.28524)
			(mid -5.569966 1.563565)
			(end -6.204966 1.28524)
			(stroke
				(width 0.3048)
				(type default)
			)
			(layer "B.SilkS")
		)
		(fp_arc
			(start -3.664966 0.114808)
			(mid -3.029966 -0.163517)
			(end -2.394966 0.114808)
			(stroke
				(width 0.3048)
				(type default)
			)
			(layer "B.SilkS")
		)
		(fp_arc
			(start -3.664966 1.28524)
			(mid -4.299966 1.563565)
			(end -4.934966 1.28524)
			(stroke
				(width 0.3048)
				(type default)
			)
			(layer "B.SilkS")
		)
		(fp_arc
			(start -2.394966 0.114808)
			(mid -0.896364 0.700048)
			(end -2.394966 1.28524)
			(stroke
				(width 0.3048)
				(type default)
			)
			(layer "B.SilkS")
		)
		(fp_arc
			(start -2.394966 1.28524)
			(mid -3.029966 1.563565)
			(end -3.664966 1.28524)
			(stroke
				(width 0.3048)
				(type default)
			)
			(layer "B.SilkS")
		)
		(fp_arc
			(start 3.68808 0.649224)
			(mid 4.134076 -0.044139)
			(end 4.949952 0.074168)
			(stroke
				(width 0.3048)
				(type default)
			)
			(layer "B.SilkS")
		)
		(fp_arc
			(start 4.949952 0.074168)
			(mid 5.450078 -0.112888)
			(end 5.950204 0.074168)
			(stroke
				(width 0.3048)
				(type default)
			)
			(layer "B.SilkS")
		)
		(fp_arc
			(start 4.949952 1.32588)
			(mid 4.134088 1.444178)
			(end 3.68808 0.750824)
			(stroke
				(width 0.3048)
				(type default)
			)
			(layer "B.SilkS")
		)
		(fp_arc
			(start 5.950204 0.074168)
			(mid 6.450076 -0.112722)
			(end 6.949948 0.074168)
			(stroke
				(width 0.3048)
				(type default)
			)
			(layer "B.SilkS")
		)
		(fp_arc
			(start 5.950204 1.32588)
			(mid 5.450078 1.512936)
			(end 4.949952 1.32588)
			(stroke
				(width 0.3048)
				(type default)
			)
			(layer "B.SilkS")
		)
		(fp_arc
			(start 6.949948 0.074168)
			(mid 7.450074 -0.112888)
			(end 7.9502 0.074168)
			(stroke
				(width 0.3048)
				(type default)
			)
			(layer "B.SilkS")
		)
		(fp_arc
			(start 6.949948 1.32588)
			(mid 6.450076 1.51277)
			(end 5.950204 1.32588)
			(stroke
				(width 0.3048)
				(type default)
			)
			(layer "B.SilkS")
		)
		(fp_arc
			(start 7.9502 0.074168)
			(mid 8.450072 -0.112722)
			(end 8.949944 0.074168)
			(stroke
				(width 0.3048)
				(type default)
			)
			(layer "B.SilkS")
		)
		(fp_arc
			(start 7.9502 1.32588)
			(mid 7.450074 1.512936)
			(end 6.949948 1.32588)
			(stroke
				(width 0.3048)
				(type default)
			)
			(layer "B.SilkS")
		)
		(fp_arc
			(start 8.949944 0.074168)
			(mid 9.765935 -0.044223)
			(end 10.21207 0.649224)
			(stroke
				(width 0.3048)
				(type default)
			)
			(layer "B.SilkS")
		)
		(fp_arc
			(start 8.949944 1.32588)
			(mid 8.450072 1.51277)
			(end 7.9502 1.32588)
			(stroke
				(width 0.3048)
				(type default)
			)
			(layer "B.SilkS")
		)
		(fp_arc
			(start 10.21207 0.750824)
			(mid 9.766001 1.444362)
			(end 8.949944 1.32588)
			(stroke
				(width 0.3048)
				(type default)
			)
			(layer "B.SilkS")
		)
		(fp_poly
			(pts
				(xy 15.9512 -3.1369) (xy 15.9512 -1.2446) (xy 17.0053 -1.2446) (xy 17.0053 1.2446) (xy 15.9512 1.2446)
				(xy 15.9512 2.6797) (xy -15.9512 2.6797) (xy -15.9512 1.2446) (xy -17.0053 1.2446) (xy -17.0053 -1.2446)
				(xy -15.9512 -1.2446) (xy -15.9512 -3.1369)
			)
			(stroke
				(width 0)
				(type default)
			)
			(fill no)
			(layer "B.CrtYd")
		)
		(fp_poly
			(pts
				(xy 18.0594 3.1877) (xy 18.0594 -3.6449) (xy -18.0594 -3.6449) (xy -18.0594 3.1877) (xy 0.4953 3.1877)
				(xy 0.4953 2.6797) (xy -15.9512 2.6797) (xy -15.9512 1.2446) (xy -17.0053 1.2446) (xy -17.0053 -1.2446)
				(xy -15.9512 -1.2446) (xy -15.9512 -3.1369) (xy 15.9512 -3.1369) (xy 15.9512 -1.2446) (xy 17.0053 -1.2446)
				(xy 17.0053 1.2446) (xy 15.9512 1.2446) (xy 15.9512 2.6797) (xy 0.508 2.6797) (xy 0.508 3.1877)
			)
			(stroke
				(width 0)
				(type default)
			)
			(fill no)
			(layer "B.CrtYd")
		)
		(fp_rect
			(start 18.0594 3.1877)
			(end -18.0594 -3.6449)
			(stroke
				(width 0)
				(type default)
			)
			(fill no)
			(layer "B.Fab")
		)
		(pad "" np_thru_hole circle
			(at -12.500102 -1.400048 180)
			(size 0.254 0.254)
			(drill 1.651)
			(layers "*.Cu" "*.Mask")
			(clearance 1.0541)
			(thermal_gap 1.0541)
		)
		(pad "" np_thru_hole circle
			(at 12.500102 -1.400048 180)
			(size 0.254 0.254)
			(drill 1.651)
			(layers "*.Cu" "*.Mask")
			(clearance 1.0541)
			(thermal_gap 1.0541)
		)
		(pad "H1" smd rect
			(at -16.249904 0 180)
			(size 2.5908 3.683)
			(layers "B.Cu" "B.Mask" "B.Paste")
			(net "GND")
		)
		(pad "H2" smd rect
			(at 16.249904 0 180)
			(size 2.5908 3.683)
			(layers "B.Cu" "B.Mask" "B.Paste")
			(net "GND")
		)
		(pad "P1" thru_hole oval
			(at 4.45008 0.700024 180)
			(size 0.8128 0.9144)
			(drill 0.5588)
			(layers "*.Cu" "*.Mask")
			(remove_unused_layers no)
			(net "P5V_HDD_SATA")
			(clearance 0.2286)
			(thermal_gap 0.2286)
		)
		(pad "P2" thru_hole oval
			(at 5.450078 0.700024 180)
			(size 0.8128 0.9144)
			(drill 0.5588)
			(layers "*.Cu" "*.Mask")
			(remove_unused_layers no)
			(net "P5V_HDD_SATA")
			(clearance 0.2286)
			(thermal_gap 0.2286)
		)
		(pad "P3" thru_hole oval
			(at 6.450076 0.700024 180)
			(size 0.8128 0.9144)
			(drill 0.5588)
			(layers "*.Cu" "*.Mask")
			(remove_unused_layers no)
			(net "GND")
			(clearance 0.2286)
			(thermal_gap 0.2286)
		)
		(pad "P4" thru_hole oval
			(at 7.450074 0.700024 180)
			(size 0.8128 0.9144)
			(drill 0.5588)
			(layers "*.Cu" "*.Mask")
			(remove_unused_layers no)
			(net "GND")
			(clearance 0.2286)
			(thermal_gap 0.2286)
		)
		(pad "P5" thru_hole oval
			(at 8.450072 0.700024 180)
			(size 0.8128 0.9144)
			(drill 0.5588)
			(layers "*.Cu" "*.Mask")
			(remove_unused_layers no)
			(net "P12V_HDD_SATA")
			(clearance 0.2286)
			(thermal_gap 0.2286)
		)
		(pad "P6" thru_hole oval
			(at 9.45007 0.700024 180)
			(size 0.8128 0.9144)
			(drill 0.5588)
			(layers "*.Cu" "*.Mask")
			(remove_unused_layers no)
			(net "P12V_HDD_SATA")
			(clearance 0.2286)
			(thermal_gap 0.2286)
		)
		(pad "S1" thru_hole circle
			(at -9.379966 0.700024 180)
			(size 1.016 1.016)
			(drill 0.6604)
			(layers "*.Cu" "*.Mask")
			(remove_unused_layers no)
			(net "GND")
			(clearance 0.1778)
			(thermal_gap 0.1778)
		)
		(pad "S2" thru_hole circle
			(at -8.109966 0.700024 180)
			(size 1.016 1.016)
			(drill 0.6604)
			(layers "*.Cu" "*.Mask")
			(remove_unused_layers no)
			(net "SATA6G_S1_TX_C_DP")
			(clearance 0.1778)
			(thermal_gap 0.1778)
		)
		(pad "S3" thru_hole circle
			(at -6.839966 0.700024 180)
			(size 1.016 1.016)
			(drill 0.6604)
			(layers "*.Cu" "*.Mask")
			(remove_unused_layers no)
			(net "SATA6G_S1_TX_C_DN")
			(clearance 0.1778)
			(thermal_gap 0.1778)
		)
		(pad "S4" thru_hole circle
			(at -5.569966 0.700024 180)
			(size 1.016 1.016)
			(drill 0.6604)
			(layers "*.Cu" "*.Mask")
			(remove_unused_layers no)
			(net "GND")
			(clearance 0.1778)
			(thermal_gap 0.1778)
		)
		(pad "S5" thru_hole circle
			(at -4.299966 0.700024 180)
			(size 1.016 1.016)
			(drill 0.6604)
			(layers "*.Cu" "*.Mask")
			(remove_unused_layers no)
			(net "SATA6G_S1_RX_C_DN")
			(clearance 0.1778)
			(thermal_gap 0.1778)
		)
		(pad "S6" thru_hole circle
			(at -3.029966 0.700024 180)
			(size 1.016 1.016)
			(drill 0.6604)
			(layers "*.Cu" "*.Mask")
			(remove_unused_layers no)
			(net "SATA6G_S1_RX_C_DP")
			(clearance 0.1778)
			(thermal_gap 0.1778)
		)
		(pad "S7" thru_hole circle
			(at -1.759966 0.700024 180)
			(size 1.016 1.016)
			(drill 0.6604)
			(layers "*.Cu" "*.Mask")
			(remove_unused_layers no)
			(net "GND")
			(clearance 0.1778)
			(thermal_gap 0.1778)
		)
		(zone
			(layers "F.Cu" "B.Cu" "In1.Cu" "In2.Cu" "In3.Cu" "In4.Cu" "In5.Cu" "In6.Cu"
				"In7.Cu" "In8.Cu" "In9.Cu" "In10.Cu" "In11.Cu" "In12.Cu"
			)
			(hatch none 0.5)
			(connect_pads
				(clearance 0)
			)
			(min_thickness 0.25)
			(keepout
				(tracks not_allowed)
				(vias allowed)
				(pads allowed)
				(copperpour not_allowed)
				(footprints allowed)
			)
			(placement
				(enabled no)
				(sheetname "")
			)
			(fill
				(thermal_gap 0.5)
				(thermal_bridge_width 0.5)
				(island_removal_mode 0)
			)
			(polygon
				(pts
					(arc
						(start 426.560234 -138.444986)
						(mid 424.299634 -138.444986)
						(end 426.560234 -138.444986)
					)
				)
			)
		)
		(zone
			(layers "F.Cu" "B.Cu" "In1.Cu" "In2.Cu" "In3.Cu" "In4.Cu" "In5.Cu" "In6.Cu"
				"In7.Cu" "In8.Cu" "In9.Cu" "In10.Cu" "In11.Cu" "In12.Cu"
			)
			(hatch none 0.5)
			(connect_pads
				(clearance 0)
			)
			(min_thickness 0.25)
			(keepout
				(tracks not_allowed)
				(vias allowed)
				(pads allowed)
				(copperpour not_allowed)
				(footprints allowed)
			)
			(placement
				(enabled no)
				(sheetname "")
			)
			(fill
				(thermal_gap 0.5)
				(thermal_bridge_width 0.5)
				(island_removal_mode 0)
			)
			(polygon
				(pts
					(arc
						(start 451.560438 -138.444986)
						(mid 449.299838 -138.444986)
						(end 451.560438 -138.444986)
					)
				)
			)
		)
	)
	(footprint ""
		(layer "B.Cu")
		(at 363.87024 -137.52957 90)
		(property "Reference" "R3L13"
			(at 0 0 90)
			(layer "B.SilkS")
			(hide yes)
			(effects
				(font
					(size 1.27 1.27)
				)
				(justify mirror)
			)
		)
		(property "Value" ""
			(at 0 0 90)
			(layer "B.Fab")
			(effects
				(font
					(size 1.27 1.27)
				)
				(justify mirror)
			)
		)
		(duplicate_pad_numbers_are_jumpers no)
		(fp_rect
			(start -0.2794 -0.1016)
			(end 0.2794 0.9906)
			(stroke
				(width 0)
				(type default)
			)
			(fill no)
			(layer "B.CrtYd")
		)
		(fp_line
			(start 0.2794 -0.1016)
			(end 0.2794 0.9906)
			(stroke
				(width 0.1)
				(type default)
			)
			(layer "B.Fab")
		)
		(fp_line
			(start -0.2794 -0.1016)
			(end 0.2794 -0.1016)
			(stroke
				(width 0.1)
				(type default)
			)
			(layer "B.Fab")
		)
		(fp_line
			(start 0.2794 0.9906)
			(end -0.2794 0.9906)
			(stroke
				(width 0.1)
				(type default)
			)
			(layer "B.Fab")
		)
		(fp_line
			(start -0.2794 0.9906)
			(end -0.2794 -0.1016)
			(stroke
				(width 0.1)
				(type default)
			)
			(layer "B.Fab")
		)
		(pad "1" smd rect
			(at 0 0 270)
			(size 0.508 0.508)
			(layers "B.Cu" "B.Mask" "B.Paste")
			(net "PVCCIO_CPU0")
		)
		(pad "2" smd rect
			(at 0 0.889 270)
			(size 0.508 0.508)
			(layers "B.Cu" "B.Mask" "B.Paste")
			(net "SVID_CLK1_CPU0_R")
		)
		(zone
			(layer "B.Cu")
			(hatch none 0.5)
			(connect_pads
				(clearance 0)
			)
			(min_thickness 0.25)
			(keepout
				(tracks allowed)
				(vias not_allowed)
				(pads allowed)
				(copperpour not_allowed)
				(footprints allowed)
			)
			(placement
				(enabled no)
				(sheetname "")
			)
			(fill
				(thermal_gap 0.5)
				(thermal_bridge_width 0.5)
				(island_removal_mode 0)
			)
			(polygon
				(pts
					(xy 364.12424 -137.27557) (xy 364.50524 -137.27557) (xy 364.50524 -137.78357) (xy 364.12424 -137.78357)
				)
			)
		)
		(zone
			(layer "B.Cu")
			(hatch none 0.5)
			(connect_pads
				(clearance 0)
			)
			(min_thickness 0.25)
			(keepout
				(tracks not_allowed)
				(vias allowed)
				(pads allowed)
				(copperpour not_allowed)
				(footprints allowed)
			)
			(placement
				(enabled no)
				(sheetname "")
			)
			(fill
				(thermal_gap 0.5)
				(thermal_bridge_width 0.5)
				(island_removal_mode 0)
			)
			(polygon
				(pts
					(xy 364.12424 -137.27557) (xy 364.50524 -137.27557) (xy 364.50524 -137.78357) (xy 364.12424 -137.78357)
				)
			)
		)
	)
	(footprint ""
		(layer "B.Cu")
		(at 488.50804 -123.55068)
		(property "Reference" "C1M4"
			(at 0 0 0)
			(layer "B.SilkS")
			(hide yes)
			(effects
				(font
					(size 1.27 1.27)
				)
				(justify mirror)
			)
		)
		(property "Value" ""
			(at 0 0 0)
			(layer "B.Fab")
			(effects
				(font
					(size 1.27 1.27)
				)
				(justify mirror)
			)
		)
		(duplicate_pad_numbers_are_jumpers no)
		(fp_rect
			(start 0.3048 -0.1016)
			(end -0.3048 0.9906)
			(stroke
				(width 0)
				(type default)
			)
			(fill no)
			(layer "B.CrtYd")
		)
		(fp_line
			(start -0.3048 -0.1016)
			(end 0.3048 -0.1016)
			(stroke
				(width 0.1)
				(type default)
			)
			(layer "B.Fab")
		)
		(fp_line
			(start -0.3048 0.9906)
			(end -0.3048 -0.1016)
			(stroke
				(width 0.1)
				(type default)
			)
			(layer "B.Fab")
		)
		(fp_line
			(start 0.3048 -0.1016)
			(end 0.3048 0.9906)
			(stroke
				(width 0.1)
				(type default)
			)
			(layer "B.Fab")
		)
		(fp_line
			(start 0.3048 0.9906)
			(end -0.3048 0.9906)
			(stroke
				(width 0.1)
				(type default)
			)
			(layer "B.Fab")
		)
		(pad "1" smd rect
			(at 0 0 180)
			(size 0.508 0.508)
			(layers "B.Cu" "B.Mask" "B.Paste")
			(net "ISENSE_TMP421_1_DXP")
		)
		(pad "2" smd rect
			(at 0 0.889 180)
			(size 0.508 0.508)
			(layers "B.Cu" "B.Mask" "B.Paste")
			(net "ISENSE_TMP421_1_DXN")
		)
		(zone
			(layer "B.Cu")
			(hatch none 0.5)
			(connect_pads
				(clearance 0)
			)
			(min_thickness 0.25)
			(keepout
				(tracks not_allowed)
				(vias allowed)
				(pads allowed)
				(copperpour not_allowed)
				(footprints allowed)
			)
			(placement
				(enabled no)
				(sheetname "")
			)
			(fill
				(thermal_gap 0.5)
				(thermal_bridge_width 0.5)
				(island_removal_mode 0)
			)
			(polygon
				(pts
					(xy 488.76204 -123.29668) (xy 488.25404 -123.29668) (xy 488.25404 -122.91568) (xy 488.76204 -122.91568)
				)
			)
		)
		(zone
			(layer "B.Cu")
			(hatch none 0.5)
			(connect_pads
				(clearance 0)
			)
			(min_thickness 0.25)
			(keepout
				(tracks allowed)
				(vias not_allowed)
				(pads allowed)
				(copperpour not_allowed)
				(footprints allowed)
			)
			(placement
				(enabled no)
				(sheetname "")
			)
			(fill
				(thermal_gap 0.5)
				(thermal_bridge_width 0.5)
				(island_removal_mode 0)
			)
			(polygon
				(pts
					(xy 488.76204 -123.29668) (xy 488.25404 -123.29668) (xy 488.25404 -122.91568) (xy 488.76204 -122.91568)
				)
			)
		)
	)
)
